(kicad_pcb
	(version 20260206)
	(generator "pcbnew")
	(generator_version "10.0")
	(general
		(thickness 1.6)
		(legacy_teardrops no)
	)
	(paper "A4")
	(title_block
		(title "dpb — 14545-sa.0730WZS0815.brd")
		(comment 1 "Honey Badger (Wiwynn) / footprints 469-474 of 1066")
	)
	(layers
		(0 "F.Cu" signal "TOP")
		(4 "In1.Cu" signal "L2GND")
		(6 "In2.Cu" signal "L3")
		(8 "In3.Cu" signal "L4VCC")
		(10 "In4.Cu" signal "L5VCC")
		(12 "In5.Cu" signal "L6")
		(14 "In6.Cu" signal "L7GND")
		(2 "B.Cu" signal "BOTTOM")
		(9 "F.Adhes" user "F.Adhesive")
		(11 "B.Adhes" user "B.Adhesive")
		(13 "F.Paste" user "Package Geometry/Pastemask Top")
		(15 "B.Paste" user "Package Geometry/Pastemask Bottom")
		(5 "F.SilkS" user "Ref Des/Silkscreen Top")
		(7 "B.SilkS" user "Ref Des/Silkscreen Bottom")
		(1 "F.Mask" user "Board Geometry/Soldermask Top")
		(3 "B.Mask" user "Board Geometry/Soldermask Bottom")
		(17 "Dwgs.User" user "User.Drawings")
		(19 "Cmts.User" user "User.Comments")
		(21 "Eco1.User" user "User.Eco1")
		(23 "Eco2.User" user "User.Eco2")
		(25 "Edge.Cuts" user "Board Geometry/Outline")
		(27 "Margin" user)
		(31 "F.CrtYd" user "Package Geometry/Place Bound Top")
		(29 "B.CrtYd" user "Package Geometry/Place Bound Bottom")
		(35 "F.Fab" user "Ref Des/Assembly Top")
		(33 "B.Fab" user "Ref Des/Assembly Bottom")
	)
	(footprint ""
		(layer "F.Cu")
		(at 52.07 -418.973 90)
		(property "Reference" "R558"
			(at 0 0 90)
			(layer "F.SilkS")
			(hide yes)
			(effects
				(font
					(size 1.27 1.27)
				)
			)
		)
		(property "Value" "200KR2F-L-GP"
			(at 0.064008 -3.993896 90)
			(unlocked yes)
			(layer "F.Fab")
			(hide yes)
			(effects
				(font
					(size 1.016 1.016)
					(thickness 0.1524)
				)
			)
		)
		(property "Device Type" "R402H16"
			(at 0.064008 -5.517896 90)
			(unlocked yes)
			(layer "F.Fab")
			(hide yes)
			(effects
				(font
					(size 1.016 1.016)
					(thickness 0.1524)
				)
			)
		)
		(duplicate_pad_numbers_are_jumpers no)
		(fp_line
			(start 0.508 -0.9398)
			(end -0.508 -0.9398)
			(stroke
				(width 0.1524)
				(type default)
			)
			(layer "F.SilkS")
		)
		(fp_line
			(start -0.508 -0.9398)
			(end -0.508 0.9398)
			(stroke
				(width 0.1524)
				(type default)
			)
			(layer "F.SilkS")
		)
		(fp_rect
			(start -0.508 0.9398)
			(end 0.508 -0.9398)
			(stroke
				(width 0)
				(type default)
			)
			(fill no)
			(layer "F.CrtYd")
		)
		(fp_rect
			(start -0.508 0.9398)
			(end 0.508 -0.9398)
			(stroke
				(width 0)
				(type default)
			)
			(fill no)
			(layer "F.Fab")
		)
		(pad "1" smd custom
			(at 0 -0.4445 90)
			(size 0.1397 0.1397)
			(layers "F.Cu" "F.Mask" "F.Paste")
			(net "SW_HDD10_R")
			(options
				(clearance outline)
				(anchor circle)
			)
			(primitives
				(gr_poly
					(pts
						(arc
							(start -0.1778 -0.2794)
							(mid -0.249642 -0.249642)
							(end -0.2794 -0.1778)
						)
						(arc
							(start -0.2794 0.1778)
							(mid -0.249642 0.249642)
							(end -0.1778 0.2794)
						)
						(arc
							(start 0.1778 0.2794)
							(mid 0.249642 0.249642)
							(end 0.2794 0.1778)
						)
						(arc
							(start 0.2794 -0.1778)
							(mid 0.249642 -0.249642)
							(end 0.1778 -0.2794)
						)
					)
					(width 0)
					(fill yes)
				)
			)
		)
		(pad "2" smd custom
			(at 0 0.4445 90)
			(size 0.1397 0.1397)
			(layers "F.Cu" "F.Mask" "F.Paste")
			(net "SW_HDD10_N")
			(options
				(clearance outline)
				(anchor circle)
			)
			(primitives
				(gr_poly
					(pts
						(arc
							(start -0.1778 -0.2794)
							(mid -0.249642 -0.249642)
							(end -0.2794 -0.1778)
						)
						(arc
							(start -0.2794 0.1778)
							(mid -0.249642 0.249642)
							(end -0.1778 0.2794)
						)
						(arc
							(start 0.1778 0.2794)
							(mid 0.249642 0.249642)
							(end 0.2794 0.1778)
						)
						(arc
							(start 0.2794 -0.1778)
							(mid 0.249642 -0.249642)
							(end 0.1778 -0.2794)
						)
					)
					(width 0)
					(fill yes)
				)
			)
		)
	)
	(footprint ""
		(layer "F.Cu")
		(at 25.527 -282.829)
		(property "Reference" "R204"
			(at 0 0 0)
			(layer "F.SilkS")
			(hide yes)
			(effects
				(font
					(size 1.27 1.27)
				)
			)
		)
		(property "Value" "4K7R2J-2-GP"
			(at 0.064008 -3.993896 0)
			(unlocked yes)
			(layer "F.Fab")
			(hide yes)
			(effects
				(font
					(size 1.016 1.016)
					(thickness 0.1524)
				)
			)
		)
		(property "Device Type" "R402H16"
			(at 0.064008 -5.517896 0)
			(unlocked yes)
			(layer "F.Fab")
			(hide yes)
			(effects
				(font
					(size 1.016 1.016)
					(thickness 0.1524)
				)
			)
		)
		(duplicate_pad_numbers_are_jumpers no)
		(fp_line
			(start -0.508 -0.9398)
			(end -0.508 0.9398)
			(stroke
				(width 0.1524)
				(type default)
			)
			(layer "F.SilkS")
		)
		(fp_line
			(start 0.508 -0.9398)
			(end -0.508 -0.9398)
			(stroke
				(width 0.1524)
				(type default)
			)
			(layer "F.SilkS")
		)
		(fp_rect
			(start -0.508 0.9398)
			(end 0.508 -0.9398)
			(stroke
				(width 0)
				(type default)
			)
			(fill no)
			(layer "F.CrtYd")
		)
		(fp_rect
			(start -0.508 0.9398)
			(end 0.508 -0.9398)
			(stroke
				(width 0)
				(type default)
			)
			(fill no)
			(layer "F.Fab")
		)
		(pad "1" smd custom
			(at 0 -0.4445)
			(size 0.1397 0.1397)
			(layers "F.Cu" "F.Mask" "F.Paste")
			(net "P12V")
			(options
				(clearance outline)
				(anchor circle)
			)
			(primitives
				(gr_poly
					(pts
						(arc
							(start -0.1778 -0.2794)
							(mid -0.249642 -0.249642)
							(end -0.2794 -0.1778)
						)
						(arc
							(start -0.2794 0.1778)
							(mid -0.249642 0.249642)
							(end -0.1778 0.2794)
						)
						(arc
							(start 0.1778 0.2794)
							(mid 0.249642 0.249642)
							(end 0.2794 0.1778)
						)
						(arc
							(start 0.2794 -0.1778)
							(mid 0.249642 -0.249642)
							(end 0.1778 -0.2794)
						)
					)
					(width 0)
					(fill yes)
				)
			)
		)
		(pad "2" smd custom
			(at 0 0.4445)
			(size 0.1397 0.1397)
			(layers "F.Cu" "F.Mask" "F.Paste")
			(net "SW_HDD7_R")
			(options
				(clearance outline)
				(anchor circle)
			)
			(primitives
				(gr_poly
					(pts
						(arc
							(start -0.1778 -0.2794)
							(mid -0.249642 -0.249642)
							(end -0.2794 -0.1778)
						)
						(arc
							(start -0.2794 0.1778)
							(mid -0.249642 0.249642)
							(end -0.1778 0.2794)
						)
						(arc
							(start 0.1778 0.2794)
							(mid 0.249642 0.249642)
							(end 0.2794 0.1778)
						)
						(arc
							(start 0.2794 -0.1778)
							(mid 0.249642 -0.249642)
							(end 0.1778 -0.2794)
						)
					)
					(width 0)
					(fill yes)
				)
			)
		)
	)
	(footprint ""
		(layer "F.Cu")
		(at 33.273746 -263.9187 -90)
		(property "Reference" "C215"
			(at 0 0 270)
			(layer "F.SilkS")
			(hide yes)
			(effects
				(font
					(size 1.27 1.27)
				)
			)
		)
		(property "Value" "SCD01U50V2KX-1GP"
			(at 1.1811 -2.7051 270)
			(unlocked yes)
			(layer "F.Fab")
			(hide yes)
			(effects
				(font
					(size 1.016 1.016)
					(thickness 0.1524)
				)
			)
		)
		(property "Device Type" "C402H22"
			(at 1.1811 -4.2291 270)
			(unlocked yes)
			(layer "F.Fab")
			(hide yes)
			(effects
				(font
					(size 1.016 1.016)
					(thickness 0.1524)
				)
			)
		)
		(duplicate_pad_numbers_are_jumpers no)
		(fp_rect
			(start -0.4318 0.9525)
			(end 0.4318 -0.9525)
			(stroke
				(width 0)
				(type default)
			)
			(fill no)
			(layer "F.CrtYd")
		)
		(fp_rect
			(start -0.4318 0.9525)
			(end 0.4318 -0.9525)
			(stroke
				(width 0)
				(type default)
			)
			(fill no)
			(layer "F.Fab")
		)
		(pad "1" smd custom
			(at 0 -0.4445 270)
			(size 0.1524 0.1524)
			(layers "F.Cu" "F.Mask" "F.Paste")
			(net "SAS2X28_DRIVE_RX_P_A7")
			(options
				(clearance outline)
				(anchor circle)
			)
			(primitives
				(gr_poly
					(pts
						(arc
							(start 0.3048 -0.2032)
							(mid 0.275042 -0.275042)
							(end 0.2032 -0.3048)
						)
						(arc
							(start -0.2032 -0.3048)
							(mid -0.275042 -0.275042)
							(end -0.3048 -0.2032)
						)
						(arc
							(start -0.3048 0.2032)
							(mid -0.275042 0.275042)
							(end -0.2032 0.3048)
						)
						(arc
							(start 0.2032 0.3048)
							(mid 0.275042 0.275042)
							(end 0.3048 0.2032)
						)
					)
					(width 0)
					(fill yes)
				)
			)
		)
		(pad "2" smd custom
			(at 0 0.4445 270)
			(size 0.1524 0.1524)
			(layers "F.Cu" "F.Mask" "F.Paste")
			(net "SAS2X28_A_HDD7_RX_+")
			(options
				(clearance outline)
				(anchor circle)
			)
			(primitives
				(gr_poly
					(pts
						(arc
							(start 0.3048 -0.2032)
							(mid 0.275042 -0.275042)
							(end 0.2032 -0.3048)
						)
						(arc
							(start -0.2032 -0.3048)
							(mid -0.275042 -0.275042)
							(end -0.3048 -0.2032)
						)
						(arc
							(start -0.3048 0.2032)
							(mid -0.275042 0.275042)
							(end -0.2032 0.3048)
						)
						(arc
							(start 0.2032 0.3048)
							(mid 0.275042 0.275042)
							(end 0.3048 0.2032)
						)
					)
					(width 0)
					(fill yes)
				)
			)
		)
	)
	(footprint ""
		(layer "F.Cu")
		(at 78.994 -196.342)
		(property "Reference" "R571"
			(at 0 0 0)
			(layer "F.SilkS")
			(hide yes)
			(effects
				(font
					(size 1.27 1.27)
				)
			)
		)
		(property "Value" "300KR2F-GP"
			(at 0.064008 -3.993896 0)
			(unlocked yes)
			(layer "F.Fab")
			(hide yes)
			(effects
				(font
					(size 1.016 1.016)
					(thickness 0.1524)
				)
			)
		)
		(property "Device Type" "R402H16"
			(at 0.064008 -5.517896 0)
			(unlocked yes)
			(layer "F.Fab")
			(hide yes)
			(effects
				(font
					(size 1.016 1.016)
					(thickness 0.1524)
				)
			)
		)
		(duplicate_pad_numbers_are_jumpers no)
		(fp_line
			(start -0.508 -0.9398)
			(end -0.508 0.9398)
			(stroke
				(width 0.1524)
				(type default)
			)
			(layer "F.SilkS")
		)
		(fp_line
			(start 0.508 -0.9398)
			(end -0.508 -0.9398)
			(stroke
				(width 0.1524)
				(type default)
			)
			(layer "F.SilkS")
		)
		(fp_rect
			(start -0.508 0.9398)
			(end 0.508 -0.9398)
			(stroke
				(width 0)
				(type default)
			)
			(fill no)
			(layer "F.CrtYd")
		)
		(fp_rect
			(start -0.508 0.9398)
			(end 0.508 -0.9398)
			(stroke
				(width 0)
				(type default)
			)
			(fill no)
			(layer "F.Fab")
		)
		(pad "1" smd custom
			(at 0 -0.4445)
			(size 0.1397 0.1397)
			(layers "F.Cu" "F.Mask" "F.Paste")
			(net "SW_HDD8_N")
			(options
				(clearance outline)
				(anchor circle)
			)
			(primitives
				(gr_poly
					(pts
						(arc
							(start -0.1778 -0.2794)
							(mid -0.249642 -0.249642)
							(end -0.2794 -0.1778)
						)
						(arc
							(start -0.2794 0.1778)
							(mid -0.249642 0.249642)
							(end -0.1778 0.2794)
						)
						(arc
							(start 0.1778 0.2794)
							(mid 0.249642 0.249642)
							(end 0.2794 0.1778)
						)
						(arc
							(start 0.2794 -0.1778)
							(mid 0.249642 -0.249642)
							(end 0.1778 -0.2794)
						)
					)
					(width 0)
					(fill yes)
				)
			)
		)
		(pad "2" smd custom
			(at 0 0.4445)
			(size 0.1397 0.1397)
			(layers "F.Cu" "F.Mask" "F.Paste")
			(net "P12V")
			(options
				(clearance outline)
				(anchor circle)
			)
			(primitives
				(gr_poly
					(pts
						(arc
							(start -0.1778 -0.2794)
							(mid -0.249642 -0.249642)
							(end -0.2794 -0.1778)
						)
						(arc
							(start -0.2794 0.1778)
							(mid -0.249642 0.249642)
							(end -0.1778 0.2794)
						)
						(arc
							(start 0.1778 0.2794)
							(mid 0.249642 0.249642)
							(end 0.2794 0.1778)
						)
						(arc
							(start 0.2794 -0.1778)
							(mid 0.249642 -0.249642)
							(end 0.1778 -0.2794)
						)
					)
					(width 0)
					(fill yes)
				)
			)
		)
	)
	(footprint ""
		(layer "F.Cu")
		(at 48.208946 -246.9134 90)
		(property "Reference" "Q41"
			(at 0 0 90)
			(layer "F.SilkS")
			(hide yes)
			(effects
				(font
					(size 1.27 1.27)
				)
			)
		)
		(property "Value" "PMBS3904-1-GP"
			(at 0 -9.0932 90)
			(unlocked yes)
			(layer "F.Fab")
			(hide yes)
			(effects
				(font
					(size 1.016 1.016)
					(thickness 0.1524)
				)
			)
		)
		(property "Device Type" "SOT-23-10H44"
			(at 0 -10.6172 90)
			(unlocked yes)
			(layer "F.Fab")
			(hide yes)
			(effects
				(font
					(size 1.016 1.016)
					(thickness 0.1524)
				)
			)
		)
		(duplicate_pad_numbers_are_jumpers no)
		(fp_line
			(start 1.651 -1.778)
			(end -1.651 -1.778)
			(stroke
				(width 0.1524)
				(type default)
			)
			(layer "F.SilkS")
		)
		(fp_line
			(start -1.651 -1.778)
			(end -1.651 1.778)
			(stroke
				(width 0.1524)
				(type default)
			)
			(layer "F.SilkS")
		)
		(fp_line
			(start 1.651 1.778)
			(end 1.651 -1.778)
			(stroke
				(width 0.1524)
				(type default)
			)
			(layer "F.SilkS")
		)
		(fp_line
			(start -1.651 1.778)
			(end 1.651 1.778)
			(stroke
				(width 0.1524)
				(type default)
			)
			(layer "F.SilkS")
		)
		(fp_line
			(start -0.9906 1.86309)
			(end -0.701294 2.15265)
			(stroke
				(width 0.0127)
				(type default)
			)
			(layer "F.SilkS")
		)
		(fp_line
			(start -0.994156 1.8669)
			(end -0.987044 1.8669)
			(stroke
				(width 0.0127)
				(type default)
			)
			(layer "F.SilkS")
		)
		(fp_line
			(start -1.003808 1.876552)
			(end -0.977646 1.876552)
			(stroke
				(width 0.0127)
				(type default)
			)
			(layer "F.SilkS")
		)
		(fp_line
			(start -0.635 1.8796)
			(end -1.7526 1.8796)
			(stroke
				(width 0.3302)
				(type default)
			)
			(layer "F.SilkS")
		)
		(fp_line
			(start -1.7526 1.8796)
			(end -1.7526 0.9906)
			(stroke
				(width 0.3302)
				(type default)
			)
			(layer "F.SilkS")
		)
		(fp_line
			(start -1.013206 1.88595)
			(end -0.967994 1.88595)
			(stroke
				(width 0.0127)
				(type default)
			)
			(layer "F.SilkS")
		)
		(fp_line
			(start -1.022858 1.895602)
			(end -0.958596 1.895602)
			(stroke
				(width 0.0127)
				(type default)
			)
			(layer "F.SilkS")
		)
		(fp_line
			(start -1.032256 1.905)
			(end -0.948944 1.905)
			(stroke
				(width 0.0127)
				(type default)
			)
			(layer "F.SilkS")
		)
		(fp_line
			(start -1.041908 1.914652)
			(end -0.939546 1.914652)
			(stroke
				(width 0.0127)
				(type default)
			)
			(layer "F.SilkS")
		)
		(fp_line
			(start -1.051306 1.92405)
			(end -0.929894 1.92405)
			(stroke
				(width 0.0127)
				(type default)
			)
			(layer "F.SilkS")
		)
		(fp_line
			(start -1.060958 1.933702)
			(end -0.920496 1.933702)
			(stroke
				(width 0.0127)
				(type default)
			)
			(layer "F.SilkS")
		)
		(fp_line
			(start -1.070356 1.9431)
			(end -0.910844 1.9431)
			(stroke
				(width 0.0127)
				(type default)
			)
			(layer "F.SilkS")
		)
		(fp_line
			(start -1.080008 1.952752)
			(end -0.901446 1.952752)
			(stroke
				(width 0.0127)
				(type default)
			)
			(layer "F.SilkS")
		)
		(fp_line
			(start -1.089406 1.96215)
			(end -0.891794 1.96215)
			(stroke
				(width 0.0127)
				(type default)
			)
			(layer "F.SilkS")
		)
		(fp_line
			(start -1.099058 1.971802)
			(end -0.882396 1.971802)
			(stroke
				(width 0.0127)
				(type default)
			)
			(layer "F.SilkS")
		)
		(fp_line
			(start -1.108456 1.9812)
			(end -0.872744 1.9812)
			(stroke
				(width 0.0127)
				(type default)
			)
			(layer "F.SilkS")
		)
		(fp_line
			(start -1.118108 1.990852)
			(end -0.863346 1.990852)
			(stroke
				(width 0.0127)
				(type default)
			)
			(layer "F.SilkS")
		)
		(fp_line
			(start -1.127506 2.00025)
			(end -0.853694 2.00025)
			(stroke
				(width 0.0127)
				(type default)
			)
			(layer "F.SilkS")
		)
		(fp_line
			(start -1.137158 2.009902)
			(end -0.844296 2.009902)
			(stroke
				(width 0.0127)
				(type default)
			)
			(layer "F.SilkS")
		)
		(fp_line
			(start -1.146556 2.0193)
			(end -0.834644 2.0193)
			(stroke
				(width 0.0127)
				(type default)
			)
			(layer "F.SilkS")
		)
		(fp_line
			(start -1.156208 2.028952)
			(end -0.825246 2.028952)
			(stroke
				(width 0.0127)
				(type default)
			)
			(layer "F.SilkS")
		)
		(fp_line
			(start -1.165606 2.03835)
			(end -0.815594 2.03835)
			(stroke
				(width 0.0127)
				(type default)
			)
			(layer "F.SilkS")
		)
		(fp_line
			(start -1.175258 2.048002)
			(end -0.806196 2.048002)
			(stroke
				(width 0.0127)
				(type default)
			)
			(layer "F.SilkS")
		)
		(fp_line
			(start -1.184656 2.0574)
			(end -0.796544 2.0574)
			(stroke
				(width 0.0127)
				(type default)
			)
			(layer "F.SilkS")
		)
		(fp_line
			(start -1.194308 2.067052)
			(end -0.787146 2.067052)
			(stroke
				(width 0.0127)
				(type default)
			)
			(layer "F.SilkS")
		)
		(fp_line
			(start -1.203706 2.07645)
			(end -0.777494 2.07645)
			(stroke
				(width 0.0127)
				(type default)
			)
			(layer "F.SilkS")
		)
		(fp_line
			(start -1.213358 2.086102)
			(end -0.768096 2.086102)
			(stroke
				(width 0.0127)
				(type default)
			)
			(layer "F.SilkS")
		)
		(fp_line
			(start -1.222756 2.0955)
			(end -0.758444 2.0955)
			(stroke
				(width 0.0127)
				(type default)
			)
			(layer "F.SilkS")
		)
		(fp_line
			(start -1.232408 2.105152)
			(end -0.749046 2.105152)
			(stroke
				(width 0.0127)
				(type default)
			)
			(layer "F.SilkS")
		)
		(fp_line
			(start -1.241806 2.11455)
			(end -0.739394 2.11455)
			(stroke
				(width 0.0127)
				(type default)
			)
			(layer "F.SilkS")
		)
		(fp_line
			(start -1.251458 2.124202)
			(end -0.729996 2.124202)
			(stroke
				(width 0.0127)
				(type default)
			)
			(layer "F.SilkS")
		)
		(fp_line
			(start -1.260856 2.1336)
			(end -0.720344 2.1336)
			(stroke
				(width 0.0127)
				(type default)
			)
			(layer "F.SilkS")
		)
		(fp_line
			(start -0.719074 2.145538)
			(end -1.265936 2.14122)
			(stroke
				(width 0.0127)
				(type default)
			)
			(layer "F.SilkS")
		)
		(fp_line
			(start -1.279398 2.152142)
			(end -0.9906 1.86309)
			(stroke
				(width 0.0127)
				(type default)
			)
			(layer "F.SilkS")
		)
		(fp_line
			(start -0.71628 2.15265)
			(end -1.26492 2.15265)
			(stroke
				(width 0.0127)
				(type default)
			)
			(layer "F.SilkS")
		)
		(fp_line
			(start -1.279144 2.15265)
			(end -0.701294 2.15265)
			(stroke
				(width 0.0127)
				(type default)
			)
			(layer "F.SilkS")
		)
		(fp_poly
			(pts
				(xy -1.285748 2.159) (xy -1.285748 1.8796) (xy -1.778 1.8796) (xy -1.778 -1.8796) (xy 1.778 -1.8796)
				(xy 1.778 1.8796) (xy -0.694944 1.8796) (xy -0.694944 2.159)
			)
			(stroke
				(width 0)
				(type default)
			)
			(fill no)
			(layer "F.CrtYd")
		)
		(fp_poly
			(pts
				(xy -1.285748 2.159) (xy -1.285748 1.8796) (xy -1.778 1.8796) (xy -1.778 -1.8796) (xy 1.778 -1.8796)
				(xy 1.778 1.8796) (xy -0.694944 1.8796) (xy -0.694944 2.159)
			)
			(stroke
				(width 0)
				(type default)
			)
			(fill no)
			(layer "F.Fab")
		)
		(pad "1" smd rect
			(at -0.98425 0.9525 90)
			(size 0.762 1.143)
			(layers "F.Cu" "F.Mask" "F.Paste")
			(net "FLT_HDD7_B")
		)
		(pad "2" smd rect
			(at 0.98425 0.9525 90)
			(size 0.762 1.143)
			(layers "F.Cu" "F.Mask" "F.Paste")
			(net "GND")
		)
		(pad "3" smd rect
			(at 0 -0.9525 90)
			(size 0.762 1.143)
			(layers "F.Cu" "F.Mask" "F.Paste")
			(net "DRIVE_ACT_7")
		)
	)
	(footprint ""
		(layer "F.Cu")
		(at 5.206746 -334.0227)
		(property "Reference" "TP5"
			(at 0 0 0)
			(layer "F.SilkS")
			(hide yes)
			(effects
				(font
					(size 1.27 1.27)
				)
			)
		)
		(property "Value" "TPAD32-GP"
			(at 0 -3.166364 0)
			(unlocked yes)
			(layer "F.Fab")
			(hide yes)
			(effects
				(font
					(size 1.016 1.016)
					(thickness 0.1524)
				)
			)
		)
		(property "Device Type" "TPAD32"
			(at 0 -4.690618 0)
			(unlocked yes)
			(layer "F.Fab")
			(hide yes)
			(effects
				(font
					(size 1.016 1.016)
					(thickness 0.1524)
				)
			)
		)
		(duplicate_pad_numbers_are_jumpers no)
		(fp_poly
			(pts
				(arc
					(start 0.4064 0)
					(mid -0.4064 0)
					(end 0.4064 0)
				)
			)
			(stroke
				(width 0)
				(type default)
			)
			(fill no)
			(layer "F.CrtYd")
		)
		(fp_poly
			(pts
				(arc
					(start 0.7112 0)
					(mid -0.7112 0)
					(end 0.7112 0)
				)
			)
			(stroke
				(width 0)
				(type default)
			)
			(fill no)
			(layer "F.Fab")
		)
		(pad "1" smd circle
			(at 0 0)
			(size 0.8128 0.8128)
			(layers "F.Cu" "F.Mask" "F.Paste")
			(net "SAS2X28_A_PRSNT15")
		)
	)
)
